(kicad_pcb
	(version 20260206)
	(generator "pcbnew")
	(generator_version "10.0")
	(general
		(thickness 1.6)
		(legacy_teardrops no)
	)
	(paper "A4")
	(title_block
		(title "03242023_DA0F0TMBIJ0_F0T_Motherboard_J_brd_V01_OCP.brd")
		(comment 1 "Grand Teton / footprints 2344-2347 of 6105")
	)
	(layers
		(0 "F.Cu" signal "TOP")
		(4 "In1.Cu" signal "GND")
		(6 "In2.Cu" signal "IN1")
		(8 "In3.Cu" signal "GND1")
		(10 "In4.Cu" signal "IN2")
		(12 "In5.Cu" signal "GND2")
		(14 "In6.Cu" signal "IN3")
		(16 "In7.Cu" signal "GND3")
		(18 "In8.Cu" signal "VCC")
		(20 "In9.Cu" signal "VCC1")
		(22 "In10.Cu" signal "GND4")
		(24 "In11.Cu" signal "IN4")
		(26 "In12.Cu" signal "GND5")
		(28 "In13.Cu" signal "IN5")
		(30 "In14.Cu" signal "GND6")
		(32 "In15.Cu" signal "IN6")
		(34 "In16.Cu" signal "GND7")
		(2 "B.Cu" signal "BOTTOM")
		(9 "F.Adhes" user "F.Adhesive")
		(11 "B.Adhes" user "B.Adhesive")
		(13 "F.Paste" user "Package Geometry/Pastemask Top")
		(15 "B.Paste" user "Package Geometry/Pastemask Bottom")
		(5 "F.SilkS" user "Ref Des/Silkscreen Top")
		(7 "B.SilkS" user "Ref Des/Silkscreen Bottom")
		(1 "F.Mask" user "Board Geometry/Soldermask Top")
		(3 "B.Mask" user "Board Geometry/Soldermask Bottom")
		(17 "Dwgs.User" user "User.Drawings")
		(19 "Cmts.User" user "User.Comments")
		(21 "Eco1.User" user "User.Eco1")
		(23 "Eco2.User" user "User.Eco2")
		(25 "Edge.Cuts" user "Board Geometry/Outline")
		(27 "Margin" user)
		(31 "F.CrtYd" user "Package Geometry/Place Bound Top")
		(29 "B.CrtYd" user "Package Geometry/Place Bound Bottom")
		(35 "F.Fab" user "Ref Des/Assembly Top")
		(33 "B.Fab" user "Ref Des/Assembly Bottom")
	)
	(footprint ""
		(layer "F.Cu")
		(at 322.287138 -15.855188)
		(property "Reference" "R1747"
			(at 0 0 0)
			(layer "F.SilkS")
			(hide yes)
			(effects
				(font
					(size 1.27 1.27)
				)
			)
		)
		(property "Value" ""
			(at 0 0 0)
			(layer "F.Fab")
			(effects
				(font
					(size 1.27 1.27)
				)
			)
		)
		(duplicate_pad_numbers_are_jumpers no)
		(fp_line
			(start -1.651 -0.8382)
			(end 1.651 -0.8382)
			(stroke
				(width 0.1524)
				(type default)
			)
			(layer "F.SilkS")
		)
		(fp_line
			(start -1.651 0.8382)
			(end -1.651 -0.8382)
			(stroke
				(width 0.1524)
				(type default)
			)
			(layer "F.SilkS")
		)
		(fp_line
			(start 1.651 -0.8382)
			(end 1.651 0.8382)
			(stroke
				(width 0.1524)
				(type default)
			)
			(layer "F.SilkS")
		)
		(fp_line
			(start 1.651 0.8382)
			(end -1.651 0.8382)
			(stroke
				(width 0.1524)
				(type default)
			)
			(layer "F.SilkS")
		)
		(fp_line
			(start -1.559814 -0.7366)
			(end -1.559814 0.7366)
			(stroke
				(width 0.1)
				(type default)
			)
			(layer "F.Fab")
		)
		(fp_line
			(start -1.559814 0.7366)
			(end -1.524 0.7366)
			(stroke
				(width 0.1)
				(type default)
			)
			(layer "F.Fab")
		)
		(fp_line
			(start -1.524 -0.7366)
			(end -1.559814 -0.7366)
			(stroke
				(width 0.1)
				(type default)
			)
			(layer "F.Fab")
		)
		(fp_line
			(start -1.524 0.7366)
			(end 1.524 0.7366)
			(stroke
				(width 0.1)
				(type default)
			)
			(layer "F.Fab")
		)
		(fp_line
			(start 1.524 -0.7366)
			(end -1.524 -0.7366)
			(stroke
				(width 0.1)
				(type default)
			)
			(layer "F.Fab")
		)
		(fp_line
			(start 1.524 0.7366)
			(end 1.560576 0.7366)
			(stroke
				(width 0.1)
				(type default)
			)
			(layer "F.Fab")
		)
		(fp_line
			(start 1.560576 -0.7366)
			(end 1.524 -0.7366)
			(stroke
				(width 0.1)
				(type default)
			)
			(layer "F.Fab")
		)
		(fp_line
			(start 1.560576 0.7366)
			(end 1.560576 -0.7366)
			(stroke
				(width 0.1)
				(type default)
			)
			(layer "F.Fab")
		)
		(pad "1" smd rect
			(at -0.94996 0 180)
			(size 1.1176 1.3716)
			(layers "F.Cu" "F.Mask" "F.Paste")
			(net "P1V8_PCH_AUX")
		)
		(pad "2" smd rect
			(at 0.94996 0 180)
			(size 1.1176 1.3716)
			(layers "F.Cu" "F.Mask" "F.Paste")
			(net "PGPPA_AUX")
		)
	)
	(footprint ""
		(layer "F.Cu")
		(at 38.72738 -128.108202 -90)
		(property "Reference" "R2573"
			(at 0 0 270)
			(layer "F.SilkS")
			(hide yes)
			(effects
				(font
					(size 1.27 1.27)
				)
			)
		)
		(property "Value" ""
			(at 0 0 270)
			(layer "F.Fab")
			(effects
				(font
					(size 1.27 1.27)
				)
			)
		)
		(duplicate_pad_numbers_are_jumpers no)
		(fp_line
			(start -0.7874 0.4064)
			(end -0.7874 -0.4064)
			(stroke
				(width 0.1524)
				(type default)
			)
			(layer "F.SilkS")
		)
		(fp_line
			(start 0.7874 0.4064)
			(end -0.7874 0.4064)
			(stroke
				(width 0.1524)
				(type default)
			)
			(layer "F.SilkS")
		)
		(fp_line
			(start -0.7874 -0.4064)
			(end 0.7874 -0.4064)
			(stroke
				(width 0.1524)
				(type default)
			)
			(layer "F.SilkS")
		)
		(fp_line
			(start 0.7874 -0.4064)
			(end 0.7874 0.4064)
			(stroke
				(width 0.1524)
				(type default)
			)
			(layer "F.SilkS")
		)
		(fp_line
			(start -0.67945 0.3048)
			(end -0.67945 -0.305054)
			(stroke
				(width 0.1)
				(type default)
			)
			(layer "F.Fab")
		)
		(fp_line
			(start -0.12065 0.3048)
			(end -0.67945 0.3048)
			(stroke
				(width 0.1)
				(type default)
			)
			(layer "F.Fab")
		)
		(fp_line
			(start 0.120396 0.3048)
			(end 0.120396 0.2794)
			(stroke
				(width 0.1)
				(type default)
			)
			(layer "F.Fab")
		)
		(fp_line
			(start 0.67945 0.3048)
			(end 0.120396 0.3048)
			(stroke
				(width 0.1)
				(type default)
			)
			(layer "F.Fab")
		)
		(fp_line
			(start -0.12065 0.2794)
			(end -0.12065 0.3048)
			(stroke
				(width 0.1)
				(type default)
			)
			(layer "F.Fab")
		)
		(fp_line
			(start 0.120396 0.2794)
			(end -0.12065 0.2794)
			(stroke
				(width 0.1)
				(type default)
			)
			(layer "F.Fab")
		)
		(fp_line
			(start -0.12065 -0.2794)
			(end 0.12065 -0.2794)
			(stroke
				(width 0.1)
				(type default)
			)
			(layer "F.Fab")
		)
		(fp_line
			(start 0.12065 -0.2794)
			(end 0.12065 -0.3048)
			(stroke
				(width 0.1)
				(type default)
			)
			(layer "F.Fab")
		)
		(fp_line
			(start 0.12065 -0.3048)
			(end 0.67945 -0.3048)
			(stroke
				(width 0.1)
				(type default)
			)
			(layer "F.Fab")
		)
		(fp_line
			(start 0.67945 -0.3048)
			(end 0.67945 0.3048)
			(stroke
				(width 0.1)
				(type default)
			)
			(layer "F.Fab")
		)
		(fp_line
			(start -0.67945 -0.305054)
			(end -0.12065 -0.305054)
			(stroke
				(width 0.1)
				(type default)
			)
			(layer "F.Fab")
		)
		(fp_line
			(start -0.12065 -0.305054)
			(end -0.12065 -0.2794)
			(stroke
				(width 0.1)
				(type default)
			)
			(layer "F.Fab")
		)
		(pad "1" smd circle
			(at -0.40005 0 270)
			(size 0 0)
			(layers "F.Cu" "F.Mask" "F.Paste")
			(net "P3V3_AUX")
		)
		(pad "2" smd circle
			(at 0.40005 0 270)
			(size 0 0)
			(layers "F.Cu" "F.Mask" "F.Paste")
			(net "IRQ_PVCCFA_CPU1_VRHOT_R_N")
		)
	)
	(footprint ""
		(layer "F.Cu")
		(at 447.687192 -22.125178 180)
		(property "Reference" "PR3781"
			(at 0 0 180)
			(layer "F.SilkS")
			(hide yes)
			(effects
				(font
					(size 1.27 1.27)
				)
			)
		)
		(property "Value" ""
			(at 0 0 180)
			(layer "F.Fab")
			(effects
				(font
					(size 1.27 1.27)
				)
			)
		)
		(duplicate_pad_numbers_are_jumpers no)
		(fp_line
			(start 0.7874 0.4064)
			(end -0.7874 0.4064)
			(stroke
				(width 0.1524)
				(type default)
			)
			(layer "F.SilkS")
		)
		(fp_line
			(start 0.7874 -0.4064)
			(end 0.7874 0.4064)
			(stroke
				(width 0.1524)
				(type default)
			)
			(layer "F.SilkS")
		)
		(fp_line
			(start -0.7874 0.4064)
			(end -0.7874 -0.4064)
			(stroke
				(width 0.1524)
				(type default)
			)
			(layer "F.SilkS")
		)
		(fp_line
			(start -0.7874 -0.4064)
			(end 0.7874 -0.4064)
			(stroke
				(width 0.1524)
				(type default)
			)
			(layer "F.SilkS")
		)
		(fp_line
			(start 0.67945 0.3048)
			(end 0.120396 0.3048)
			(stroke
				(width 0.1)
				(type default)
			)
			(layer "F.Fab")
		)
		(fp_line
			(start 0.67945 -0.3048)
			(end 0.67945 0.3048)
			(stroke
				(width 0.1)
				(type default)
			)
			(layer "F.Fab")
		)
		(fp_line
			(start 0.12065 -0.2794)
			(end 0.12065 -0.3048)
			(stroke
				(width 0.1)
				(type default)
			)
			(layer "F.Fab")
		)
		(fp_line
			(start 0.12065 -0.3048)
			(end 0.67945 -0.3048)
			(stroke
				(width 0.1)
				(type default)
			)
			(layer "F.Fab")
		)
		(fp_line
			(start 0.120396 0.3048)
			(end 0.120396 0.2794)
			(stroke
				(width 0.1)
				(type default)
			)
			(layer "F.Fab")
		)
		(fp_line
			(start 0.120396 0.2794)
			(end -0.12065 0.2794)
			(stroke
				(width 0.1)
				(type default)
			)
			(layer "F.Fab")
		)
		(fp_line
			(start -0.12065 0.3048)
			(end -0.67945 0.3048)
			(stroke
				(width 0.1)
				(type default)
			)
			(layer "F.Fab")
		)
		(fp_line
			(start -0.12065 0.2794)
			(end -0.12065 0.3048)
			(stroke
				(width 0.1)
				(type default)
			)
			(layer "F.Fab")
		)
		(fp_line
			(start -0.12065 -0.2794)
			(end 0.12065 -0.2794)
			(stroke
				(width 0.1)
				(type default)
			)
			(layer "F.Fab")
		)
		(fp_line
			(start -0.12065 -0.305054)
			(end -0.12065 -0.2794)
			(stroke
				(width 0.1)
				(type default)
			)
			(layer "F.Fab")
		)
		(fp_line
			(start -0.67945 0.3048)
			(end -0.67945 -0.305054)
			(stroke
				(width 0.1)
				(type default)
			)
			(layer "F.Fab")
		)
		(fp_line
			(start -0.67945 -0.305054)
			(end -0.12065 -0.305054)
			(stroke
				(width 0.1)
				(type default)
			)
			(layer "F.Fab")
		)
		(pad "1" smd circle
			(at -0.40005 0 180)
			(size 0 0)
			(layers "F.Cu" "F.Mask" "F.Paste")
			(net "P12V_OCP_SENSE_1")
		)
		(pad "2" smd circle
			(at 0.40005 0 180)
			(size 0 0)
			(layers "F.Cu" "F.Mask" "F.Paste")
			(net "GND")
		)
	)
	(footprint ""
		(layer "F.Cu")
		(at 292.98011 -390.459976 -90)
		(property "Reference" "PJ42"
			(at 2.072132 -8.52297 90)
			(unlocked yes)
			(layer "F.SilkS")
			(effects
				(font
					(size 0.7874 0.5842)
					(thickness 0.1524)
				)
				(justify left)
			)
		)
		(property "Value" ""
			(at 0 0 270)
			(layer "F.Fab")
			(effects
				(font
					(size 1.27 1.27)
				)
			)
		)
		(duplicate_pad_numbers_are_jumpers no)
		(fp_line
			(start -2.500122 7.649972)
			(end -2.500122 7.570978)
			(stroke
				(width 0.1524)
				(type default)
			)
			(layer "F.SilkS")
		)
		(fp_line
			(start 2.500122 7.649972)
			(end -2.500122 7.649972)
			(stroke
				(width 0.1524)
				(type default)
			)
			(layer "F.SilkS")
		)
		(fp_line
			(start 2.500122 7.570978)
			(end 2.500122 7.649972)
			(stroke
				(width 0.1524)
				(type default)
			)
			(layer "F.SilkS")
		)
		(fp_line
			(start -2.500122 5.869178)
			(end -2.500122 5.44449)
			(stroke
				(width 0.1524)
				(type default)
			)
			(layer "F.SilkS")
		)
		(fp_line
			(start 2.500122 4.944618)
			(end 2.500122 5.869178)
			(stroke
				(width 0.1524)
				(type default)
			)
			(layer "F.SilkS")
		)
		(fp_line
			(start -2.500122 -5.44449)
			(end -2.500122 -5.869178)
			(stroke
				(width 0.1524)
				(type default)
			)
			(layer "F.SilkS")
		)
		(fp_line
			(start 2.500122 -5.869178)
			(end 2.500122 -4.944618)
			(stroke
				(width 0.1524)
				(type default)
			)
			(layer "F.SilkS")
		)
		(fp_line
			(start -2.500122 -7.570978)
			(end -2.500122 -7.649972)
			(stroke
				(width 0.1524)
				(type default)
			)
			(layer "F.SilkS")
		)
		(fp_line
			(start -2.500122 -7.649972)
			(end 2.500122 -7.649972)
			(stroke
				(width 0.1524)
				(type default)
			)
			(layer "F.SilkS")
		)
		(fp_line
			(start 2.500122 -7.649972)
			(end 2.500122 -7.570978)
			(stroke
				(width 0.1524)
				(type default)
			)
			(layer "F.SilkS")
		)
		(fp_poly
			(pts
				(xy -4.094988 -5.50799) (xy -4.094988 -4.49199) (xy -3.078988 -4.99999)
			)
			(stroke
				(width 0)
				(type default)
			)
			(fill yes)
			(layer "F.SilkS")
		)
		(fp_line
			(start -2.500122 7.649972)
			(end -2.500122 -7.649972)
			(stroke
				(width 0.1)
				(type default)
			)
			(layer "F.Fab")
		)
		(fp_line
			(start 2.500122 7.649972)
			(end -2.500122 7.649972)
			(stroke
				(width 0.1)
				(type default)
			)
			(layer "F.Fab")
		)
		(fp_line
			(start -2.500122 -7.649972)
			(end 2.500122 -7.649972)
			(stroke
				(width 0.1)
				(type default)
			)
			(layer "F.Fab")
		)
		(fp_line
			(start 2.500122 -7.649972)
			(end 2.500122 7.649972)
			(stroke
				(width 0.1)
				(type default)
			)
			(layer "F.Fab")
		)
		(fp_poly
			(pts
				(xy -4.094988 -5.50799) (xy -4.094988 -4.49199) (xy -3.078988 -4.99999)
			)
			(stroke
				(width 0)
				(type default)
			)
			(fill yes)
			(layer "F.Fab")
		)
		(pad "" np_thru_hole circle
			(at 1.100074 -5.5245 180)
			(size 0.762 0.762)
			(drill 0.762)
			(layers "*.Cu" "*.Mask")
			(clearance 0.381)
			(thermal_gap 0.381)
		)
		(pad "" np_thru_hole circle
			(at 1.100074 5.5245 180)
			(size 0.762 0.762)
			(drill 0.762)
			(layers "*.Cu" "*.Mask")
			(clearance 0.381)
			(thermal_gap 0.381)
		)
		(pad "1" smd rect
			(at -2.109978 -4.99999)
			(size 0.6096 1.651)
			(layers "F.Cu" "F.Mask" "F.Paste")
			(net "P12V_PSU")
		)
		(pad "2" smd rect
			(at -2.109978 -3.999992)
			(size 0.6096 1.651)
			(layers "F.Cu" "F.Mask" "F.Paste")
			(net "P12V_HSC_SENSE1_P")
		)
		(pad "3" smd rect
			(at -2.109978 -2.999994)
			(size 0.6096 1.651)
			(layers "F.Cu" "F.Mask" "F.Paste")
			(net "P12V_HSC_SENSE1_N")
		)
		(pad "4" smd rect
			(at -2.109978 -1.999996)
			(size 0.6096 1.651)
			(layers "F.Cu" "F.Mask" "F.Paste")
			(net "P12V_HSC_SENSE2_P")
		)
		(pad "5" smd rect
			(at -2.109978 -0.999998)
			(size 0.6096 1.651)
			(layers "F.Cu" "F.Mask" "F.Paste")
			(net "P12V_HSC_SENSE2_N")
		)
		(pad "6" smd rect
			(at -2.109978 0)
			(size 0.6096 1.651)
			(layers "F.Cu" "F.Mask" "F.Paste")
			(net "P12V_HSC_ADC_N")
		)
		(pad "7" smd rect
			(at -2.109978 0.999998)
			(size 0.6096 1.651)
			(layers "F.Cu" "F.Mask" "F.Paste")
			(net "P12V_HSC_ADC_P")
		)
		(pad "8" smd rect
			(at -2.109978 1.999996)
			(size 0.6096 1.651)
			(layers "F.Cu" "F.Mask" "F.Paste")
			(net "P12V_HSC_GATE1")
		)
		(pad "9" smd rect
			(at -2.109978 2.999994)
			(size 0.6096 1.651)
			(layers "F.Cu" "F.Mask" "F.Paste")
			(net "P12V_HSC_GATE2")
		)
		(pad "10" smd rect
			(at -2.109978 3.999992)
			(size 0.6096 1.651)
			(layers "F.Cu" "F.Mask" "F.Paste")
			(net "P12V_AUX")
		)
		(pad "11" smd rect
			(at -2.109978 4.99999)
			(size 0.6096 1.651)
			(layers "F.Cu" "F.Mask" "F.Paste")
			(net "GND")
		)
		(pad "12" smd rect
			(at 2.109978 -4.500118 180)
			(size 0.6096 1.651)
			(layers "F.Cu" "F.Mask" "F.Paste")
			(net "P3V3_AUX")
		)
		(pad "13" smd rect
			(at 2.109978 -3.50012 180)
			(size 0.6096 1.651)
			(layers "F.Cu" "F.Mask" "F.Paste")
			(net "IRQ_HSC_FAULT_N")
		)
		(pad "14" smd rect
			(at 2.109978 -2.500122 180)
			(size 0.6096 1.651)
			(layers "F.Cu" "F.Mask" "F.Paste")
			(net "HSC_EN")
		)
		(pad "15" smd rect
			(at 2.109978 -1.500124 180)
			(size 0.6096 1.651)
			(layers "F.Cu" "F.Mask" "F.Paste")
			(net "MB0_P12V_STBY_PWRGD")
		)
		(pad "16" smd rect
			(at 2.109978 -0.499872 180)
			(size 0.6096 1.651)
			(layers "F.Cu" "F.Mask" "F.Paste")
			(net "HSC_CSOUT")
		)
		(pad "17" smd rect
			(at 2.109978 0.499872 180)
			(size 0.6096 1.651)
			(layers "F.Cu" "F.Mask" "F.Paste")
			(net "HSC_TYPE_ADC")
		)
		(pad "18" smd rect
			(at 2.109978 1.500124 180)
			(size 0.6096 1.651)
			(layers "F.Cu" "F.Mask" "F.Paste")
			(net "SMB_SML1_PMBUS_HSC_MODULE_SCL")
		)
		(pad "19" smd rect
			(at 2.109978 2.500122 180)
			(size 0.6096 1.651)
			(layers "F.Cu" "F.Mask" "F.Paste")
			(net "SMB_SML1_PMBUS_HSC_MODULE_SDA")
		)
		(pad "20" smd rect
			(at 2.109978 3.50012 180)
			(size 0.6096 1.651)
			(layers "F.Cu" "F.Mask" "F.Paste")
			(net "IRQ_SML1_PMBUS_ALERT_N")
		)
		(pad "21" smd rect
			(at 2.109978 4.500118 180)
			(size 0.6096 1.651)
			(layers "F.Cu" "F.Mask" "F.Paste")
			(net "GND")
		)
		(pad "G1" smd circle
			(at 0 -6.720078 180)
			(size 0 0)
			(layers "F.Cu" "F.Mask" "F.Paste")
			(net "GND")
		)
		(pad "G2" smd circle
			(at 0 6.720078 180)
			(size 0 0)
			(layers "F.Cu" "F.Mask" "F.Paste")
			(net "GND")
		)
		(zone
			(layers "F.Cu" "B.Cu" "In1.Cu" "In2.Cu" "In3.Cu" "In4.Cu" "In5.Cu" "In6.Cu"
				"In7.Cu" "In8.Cu" "In9.Cu" "In10.Cu" "In11.Cu" "In12.Cu" "In13.Cu" "In14.Cu"
				"In15.Cu" "In16.Cu"
			)
			(hatch none 0.5)
			(connect_pads
				(clearance 0)
			)
			(min_thickness 0.25)
			(keepout
				(tracks not_allowed)
				(vias allowed)
				(pads allowed)
				(copperpour not_allowed)
				(footprints allowed)
			)
			(placement
				(enabled no)
				(sheetname "")
			)
			(fill
				(thermal_gap 0.5)
				(thermal_bridge_width 0.5)
				(island_removal_mode 0)
			)
			(polygon
				(pts
					(arc
						(start 288.34461 -389.359902)
						(mid 286.56661 -389.359902)
						(end 288.34461 -389.359902)
					)
				)
			)
		)
		(zone
			(layers "F.Cu" "B.Cu" "In1.Cu" "In2.Cu" "In3.Cu" "In4.Cu" "In5.Cu" "In6.Cu"
				"In7.Cu" "In8.Cu" "In9.Cu" "In10.Cu" "In11.Cu" "In12.Cu" "In13.Cu" "In14.Cu"
				"In15.Cu" "In16.Cu"
			)
			(hatch none 0.5)
			(connect_pads
				(clearance 0)
			)
			(min_thickness 0.25)
			(keepout
				(tracks not_allowed)
				(vias allowed)
				(pads allowed)
				(copperpour not_allowed)
				(footprints allowed)
			)
			(placement
				(enabled no)
				(sheetname "")
			)
			(fill
				(thermal_gap 0.5)
				(thermal_bridge_width 0.5)
				(island_removal_mode 0)
			)
			(polygon
				(pts
					(arc
						(start 299.39361 -389.359902)
						(mid 297.61561 -389.359902)
						(end 299.39361 -389.359902)
					)
				)
			)
		)
	)
)
